(kicad_pcb
	(version 20260206)
	(generator "pcbnew")
	(generator_version "10.0")
	(general
		(thickness 1.6)
		(legacy_teardrops no)
	)
	(paper "A4")
	(title_block
		(title "peb — Lightning_PEB_BRD.brd")
		(comment 1 "Lightning (Wiwynn / Facebook NVMe JBOF) / footprints 1783-1790 of 2563")
	)
	(layers
		(0 "F.Cu" signal "TOP")
		(4 "In1.Cu" signal "L2GND")
		(6 "In2.Cu" signal "L3")
		(8 "In3.Cu" signal "L4VCC")
		(10 "In4.Cu" signal "L5VCC")
		(12 "In5.Cu" signal "L6")
		(14 "In6.Cu" signal "L7GND")
		(2 "B.Cu" signal "BOTTOM")
		(9 "F.Adhes" user "F.Adhesive")
		(11 "B.Adhes" user "B.Adhesive")
		(13 "F.Paste" user "Package Geometry/Pastemask Top")
		(15 "B.Paste" user "Package Geometry/Pastemask Bottom")
		(5 "F.SilkS" user "Ref Des/Silkscreen Top")
		(7 "B.SilkS" user "Ref Des/Silkscreen Bottom")
		(1 "F.Mask" user "Board Geometry/Soldermask Top")
		(3 "B.Mask" user "Board Geometry/Soldermask Bottom")
		(17 "Dwgs.User" user "User.Drawings")
		(19 "Cmts.User" user "User.Comments")
		(21 "Eco1.User" user "User.Eco1")
		(23 "Eco2.User" user "User.Eco2")
		(25 "Edge.Cuts" user "Board Geometry/Outline")
		(27 "Margin" user)
		(31 "F.CrtYd" user "Package Geometry/Place Bound Top")
		(29 "B.CrtYd" user "Package Geometry/Place Bound Bottom")
		(35 "F.Fab" user "Ref Des/Assembly Top")
		(33 "B.Fab" user "Ref Des/Assembly Bottom")
	)
	(footprint ""
		(layer "B.Cu")
		(at 322.537836 -38.896798)
		(property "Reference" "C255"
			(at 0 0 0)
			(layer "B.SilkS")
			(hide yes)
			(effects
				(font
					(size 1.27 1.27)
				)
				(justify mirror)
			)
		)
		(property "Value" "SCD1U10V2KX-5GP"
			(at -1.1811 -2.7051 0)
			(unlocked yes)
			(layer "B.Fab")
			(hide yes)
			(effects
				(font
					(size 1.016 1.016)
					(thickness 0.1524)
				)
				(justify mirror)
			)
		)
		(property "Device Type" "C402H22"
			(at -1.1811 -4.2291 0)
			(unlocked yes)
			(layer "B.Fab")
			(hide yes)
			(effects
				(font
					(size 1.016 1.016)
					(thickness 0.1524)
				)
				(justify mirror)
			)
		)
		(duplicate_pad_numbers_are_jumpers no)
		(fp_rect
			(start 0.4318 0.9525)
			(end -0.4318 -0.9525)
			(stroke
				(width 0)
				(type default)
			)
			(fill no)
			(layer "B.CrtYd")
		)
		(fp_rect
			(start 0.4318 0.9525)
			(end -0.4318 -0.9525)
			(stroke
				(width 0)
				(type default)
			)
			(fill no)
			(layer "B.Fab")
		)
		(pad "1" smd custom
			(at 0 -0.4445 180)
			(size 0.1524 0.1524)
			(layers "B.Cu" "B.Mask" "B.Paste")
			(net "GND")
			(options
				(clearance outline)
				(anchor circle)
			)
			(primitives
				(gr_poly
					(pts
						(arc
							(start 0.3048 0.2032)
							(mid 0.275042 0.275042)
							(end 0.2032 0.3048)
						)
						(arc
							(start -0.2032 0.3048)
							(mid -0.275042 0.275042)
							(end -0.3048 0.2032)
						)
						(arc
							(start -0.3048 -0.2032)
							(mid -0.275042 -0.275042)
							(end -0.2032 -0.3048)
						)
						(arc
							(start 0.2032 -0.3048)
							(mid 0.275042 -0.275042)
							(end 0.3048 -0.2032)
						)
					)
					(width 0)
					(fill yes)
				)
			)
		)
		(pad "2" smd custom
			(at 0 0.4445 180)
			(size 0.1524 0.1524)
			(layers "B.Cu" "B.Mask" "B.Paste")
			(net "P3V3_STBY")
			(options
				(clearance outline)
				(anchor circle)
			)
			(primitives
				(gr_poly
					(pts
						(arc
							(start 0.3048 0.2032)
							(mid 0.275042 0.275042)
							(end 0.2032 0.3048)
						)
						(arc
							(start -0.2032 0.3048)
							(mid -0.275042 0.275042)
							(end -0.3048 0.2032)
						)
						(arc
							(start -0.3048 -0.2032)
							(mid -0.275042 -0.275042)
							(end -0.2032 -0.3048)
						)
						(arc
							(start 0.2032 -0.3048)
							(mid 0.275042 -0.275042)
							(end 0.3048 -0.2032)
						)
					)
					(width 0)
					(fill yes)
				)
			)
		)
	)
	(footprint ""
		(layer "B.Cu")
		(at 56.134 -133.985 180)
		(property "Reference" "C8088"
			(at 0 0 0)
			(layer "B.SilkS")
			(hide yes)
			(effects
				(font
					(size 1.27 1.27)
				)
				(justify mirror)
			)
		)
		(property "Value" "SCD1U25V2KX-2-GP"
			(at -1.1811 -2.7051 180)
			(unlocked yes)
			(layer "B.Fab")
			(hide yes)
			(effects
				(font
					(size 1.016 1.016)
					(thickness 0.1524)
				)
				(justify mirror)
			)
		)
		(property "Device Type" "C402H22"
			(at -1.1811 -4.2291 180)
			(unlocked yes)
			(layer "B.Fab")
			(hide yes)
			(effects
				(font
					(size 1.016 1.016)
					(thickness 0.1524)
				)
				(justify mirror)
			)
		)
		(duplicate_pad_numbers_are_jumpers no)
		(fp_rect
			(start 0.4318 0.9525)
			(end -0.4318 -0.9525)
			(stroke
				(width 0)
				(type default)
			)
			(fill no)
			(layer "B.CrtYd")
		)
		(fp_rect
			(start 0.4318 0.9525)
			(end -0.4318 -0.9525)
			(stroke
				(width 0)
				(type default)
			)
			(fill no)
			(layer "B.Fab")
		)
		(pad "1" smd custom
			(at 0 -0.4445)
			(size 0.1524 0.1524)
			(layers "B.Cu" "B.Mask" "B.Paste")
			(net "ADC_P5V_STBY")
			(options
				(clearance outline)
				(anchor circle)
			)
			(primitives
				(gr_poly
					(pts
						(arc
							(start 0.3048 0.2032)
							(mid 0.275042 0.275042)
							(end 0.2032 0.3048)
						)
						(arc
							(start -0.2032 0.3048)
							(mid -0.275042 0.275042)
							(end -0.3048 0.2032)
						)
						(arc
							(start -0.3048 -0.2032)
							(mid -0.275042 -0.275042)
							(end -0.2032 -0.3048)
						)
						(arc
							(start 0.2032 -0.3048)
							(mid 0.275042 -0.275042)
							(end 0.3048 -0.2032)
						)
					)
					(width 0)
					(fill yes)
				)
			)
		)
		(pad "2" smd custom
			(at 0 0.4445)
			(size 0.1524 0.1524)
			(layers "B.Cu" "B.Mask" "B.Paste")
			(net "GND")
			(options
				(clearance outline)
				(anchor circle)
			)
			(primitives
				(gr_poly
					(pts
						(arc
							(start 0.3048 0.2032)
							(mid 0.275042 0.275042)
							(end 0.2032 0.3048)
						)
						(arc
							(start -0.2032 0.3048)
							(mid -0.275042 0.275042)
							(end -0.3048 0.2032)
						)
						(arc
							(start -0.3048 -0.2032)
							(mid -0.275042 -0.275042)
							(end -0.2032 -0.3048)
						)
						(arc
							(start 0.2032 -0.3048)
							(mid 0.275042 -0.275042)
							(end 0.3048 -0.2032)
						)
					)
					(width 0)
					(fill yes)
				)
			)
		)
	)
	(footprint ""
		(layer "B.Cu")
		(at 73.787 -37.465)
		(property "Reference" "PR26"
			(at 0 0 0)
			(layer "B.SilkS")
			(hide yes)
			(effects
				(font
					(size 1.27 1.27)
				)
				(justify mirror)
			)
		)
		(property "Value" "2KR2F-3-GP"
			(at -0.064008 -3.993896 0)
			(unlocked yes)
			(layer "B.Fab")
			(hide yes)
			(effects
				(font
					(size 1.016 1.016)
					(thickness 0.1524)
				)
				(justify mirror)
			)
		)
		(property "Device Type" "R402H16"
			(at -0.064008 -5.517896 0)
			(unlocked yes)
			(layer "B.Fab")
			(hide yes)
			(effects
				(font
					(size 1.016 1.016)
					(thickness 0.1524)
				)
				(justify mirror)
			)
		)
		(duplicate_pad_numbers_are_jumpers no)
		(fp_line
			(start -0.508 -0.9398)
			(end 0.508 -0.9398)
			(stroke
				(width 0.1524)
				(type default)
			)
			(layer "B.SilkS")
		)
		(fp_line
			(start 0.508 -0.9398)
			(end 0.508 0.9398)
			(stroke
				(width 0.1524)
				(type default)
			)
			(layer "B.SilkS")
		)
		(fp_rect
			(start 0.508 0.9398)
			(end -0.508 -0.9398)
			(stroke
				(width 0)
				(type default)
			)
			(fill no)
			(layer "B.CrtYd")
		)
		(fp_rect
			(start 0.508 0.9398)
			(end -0.508 -0.9398)
			(stroke
				(width 0)
				(type default)
			)
			(fill no)
			(layer "B.Fab")
		)
		(pad "1" smd custom
			(at 0 -0.4445 180)
			(size 0.1397 0.1397)
			(layers "B.Cu" "B.Mask" "B.Paste")
			(net "P3V3_STBY_LL")
			(options
				(clearance outline)
				(anchor circle)
			)
			(primitives
				(gr_poly
					(pts
						(arc
							(start -0.1778 0.2794)
							(mid -0.249642 0.249642)
							(end -0.2794 0.1778)
						)
						(arc
							(start -0.2794 -0.1778)
							(mid -0.249642 -0.249642)
							(end -0.1778 -0.2794)
						)
						(arc
							(start 0.1778 -0.2794)
							(mid 0.249642 -0.249642)
							(end 0.2794 -0.1778)
						)
						(arc
							(start 0.2794 0.1778)
							(mid 0.249642 0.249642)
							(end 0.1778 0.2794)
						)
					)
					(width 0)
					(fill yes)
				)
			)
		)
		(pad "2" smd custom
			(at 0 0.4445 180)
			(size 0.1397 0.1397)
			(layers "B.Cu" "B.Mask" "B.Paste")
			(net "P3V3_STBY_LL_R")
			(options
				(clearance outline)
				(anchor circle)
			)
			(primitives
				(gr_poly
					(pts
						(arc
							(start -0.1778 0.2794)
							(mid -0.249642 0.249642)
							(end -0.2794 0.1778)
						)
						(arc
							(start -0.2794 -0.1778)
							(mid -0.249642 -0.249642)
							(end -0.1778 -0.2794)
						)
						(arc
							(start 0.1778 -0.2794)
							(mid 0.249642 -0.249642)
							(end 0.2794 -0.1778)
						)
						(arc
							(start 0.2794 0.1778)
							(mid 0.249642 0.249642)
							(end 0.1778 0.2794)
						)
					)
					(width 0)
					(fill yes)
				)
			)
		)
	)
	(footprint ""
		(layer "B.Cu")
		(at 182.8546 -71.628 180)
		(property "Reference" "C619"
			(at 0 0 0)
			(layer "B.SilkS")
			(hide yes)
			(effects
				(font
					(size 1.27 1.27)
				)
				(justify mirror)
			)
		)
		(property "Value" "SC4D7U16V5KX-1-GP"
			(at 0.0762 -6.1214 180)
			(unlocked yes)
			(layer "B.Fab")
			(hide yes)
			(effects
				(font
					(size 1.016 1.016)
					(thickness 0.1524)
				)
				(justify mirror)
			)
		)
		(property "Device Type" "C805H56"
			(at 0.0762 -8.1534 180)
			(unlocked yes)
			(layer "B.Fab")
			(hide yes)
			(effects
				(font
					(size 1.016 1.016)
					(thickness 0.1524)
				)
				(justify mirror)
			)
		)
		(duplicate_pad_numbers_are_jumpers no)
		(fp_line
			(start -0.635 0)
			(end 0.635 0)
			(stroke
				(width 0.508)
				(type default)
			)
			(layer "B.SilkS")
		)
		(fp_rect
			(start 0.9652 1.778)
			(end -0.9652 -1.778)
			(stroke
				(width 0)
				(type default)
			)
			(fill no)
			(layer "B.CrtYd")
		)
		(fp_poly
			(pts
				(xy 0.9652 -1.778) (xy -0.9652 -1.778) (xy -0.9652 1.778) (xy 0.9652 1.778)
			)
			(stroke
				(width 0)
				(type default)
			)
			(fill no)
			(layer "B.Fab")
		)
		(pad "1" smd rect
			(at 0 -0.9652)
			(size 1.397 1.143)
			(layers "B.Cu" "B.Mask" "B.Paste")
			(net "DUT_AVD_PCIE")
		)
		(pad "2" smd rect
			(at 0 0.9652)
			(size 1.397 1.143)
			(layers "B.Cu" "B.Mask" "B.Paste")
			(net "GND")
		)
	)
	(footprint ""
		(layer "B.Cu")
		(at 12.9032 -85.979 180)
		(property "Reference" "C627"
			(at 0 0 0)
			(layer "B.SilkS")
			(hide yes)
			(effects
				(font
					(size 1.27 1.27)
				)
				(justify mirror)
			)
		)
		(property "Value" "SC10U6D3V5KX-4GP"
			(at 0.0762 -6.1214 180)
			(unlocked yes)
			(layer "B.Fab")
			(hide yes)
			(effects
				(font
					(size 1.016 1.016)
					(thickness 0.1524)
				)
				(justify mirror)
			)
		)
		(property "Device Type" "C805H58"
			(at 0.0762 -8.1534 180)
			(unlocked yes)
			(layer "B.Fab")
			(hide yes)
			(effects
				(font
					(size 1.016 1.016)
					(thickness 0.1524)
				)
				(justify mirror)
			)
		)
		(duplicate_pad_numbers_are_jumpers no)
		(fp_line
			(start -0.635 0)
			(end 0.635 0)
			(stroke
				(width 0.508)
				(type default)
			)
			(layer "B.SilkS")
		)
		(fp_rect
			(start 0.9652 1.778)
			(end -0.9652 -1.778)
			(stroke
				(width 0)
				(type default)
			)
			(fill no)
			(layer "B.CrtYd")
		)
		(fp_poly
			(pts
				(xy 0.9652 -1.778) (xy -0.9652 -1.778) (xy -0.9652 1.778) (xy 0.9652 1.778)
			)
			(stroke
				(width 0)
				(type default)
			)
			(fill no)
			(layer "B.Fab")
		)
		(pad "1" smd rect
			(at 0 -0.9652)
			(size 1.397 1.143)
			(layers "B.Cu" "B.Mask" "B.Paste")
			(net "P3V3_STBY")
		)
		(pad "2" smd rect
			(at 0 0.9652)
			(size 1.397 1.143)
			(layers "B.Cu" "B.Mask" "B.Paste")
			(net "GND")
		)
	)
	(footprint ""
		(layer "B.Cu")
		(at 239.8522 -25.019 90)
		(property "Reference" "TP194"
			(at 0 0 90)
			(layer "B.SilkS")
			(hide yes)
			(effects
				(font
					(size 1.27 1.27)
				)
				(justify mirror)
			)
		)
		(property "Value" "TPAD28-2-GP"
			(at 0.0127 -1.6637 90)
			(unlocked yes)
			(layer "B.Fab")
			(hide yes)
			(effects
				(font
					(size 1.016 1.016)
					(thickness 0.1524)
				)
				(justify mirror)
			)
		)
		(property "Device Type" "TPAD28"
			(at 0.0127 -3.1877 90)
			(unlocked yes)
			(layer "B.Fab")
			(hide yes)
			(effects
				(font
					(size 1.016 1.016)
					(thickness 0.1524)
				)
				(justify mirror)
			)
		)
		(duplicate_pad_numbers_are_jumpers no)
		(fp_poly
			(pts
				(arc
					(start 0 0.3556)
					(mid 0 -0.3556)
					(end 0 0.3556)
				)
			)
			(stroke
				(width 0)
				(type default)
			)
			(fill no)
			(layer "B.CrtYd")
		)
		(fp_poly
			(pts
				(arc
					(start 0 0.6096)
					(mid 0 -0.6096)
					(end 0 0.6096)
				)
			)
			(stroke
				(width 0)
				(type default)
			)
			(fill no)
			(layer "B.Fab")
		)
		(pad "1" smd circle
			(at 0 0 270)
			(size 0.7112 0.7112)
			(layers "B.Cu" "B.Mask" "B.Paste")
			(net "LBI_CE#0")
		)
	)
	(footprint ""
		(layer "B.Cu")
		(at 53.721 -138.811 90)
		(property "Reference" "R149"
			(at 0 0 90)
			(layer "B.SilkS")
			(hide yes)
			(effects
				(font
					(size 1.27 1.27)
				)
				(justify mirror)
			)
		)
		(property "Value" "4K7R2F-GP"
			(at -0.064008 -3.993896 90)
			(unlocked yes)
			(layer "B.Fab")
			(hide yes)
			(effects
				(font
					(size 1.016 1.016)
					(thickness 0.1524)
				)
				(justify mirror)
			)
		)
		(property "Device Type" "R402H16"
			(at -0.064008 -5.517896 90)
			(unlocked yes)
			(layer "B.Fab")
			(hide yes)
			(effects
				(font
					(size 1.016 1.016)
					(thickness 0.1524)
				)
				(justify mirror)
			)
		)
		(duplicate_pad_numbers_are_jumpers no)
		(fp_line
			(start 0.508 -0.9398)
			(end 0.508 0.9398)
			(stroke
				(width 0.1524)
				(type default)
			)
			(layer "B.SilkS")
		)
		(fp_line
			(start -0.508 -0.9398)
			(end 0.508 -0.9398)
			(stroke
				(width 0.1524)
				(type default)
			)
			(layer "B.SilkS")
		)
		(fp_rect
			(start 0.508 0.9398)
			(end -0.508 -0.9398)
			(stroke
				(width 0)
				(type default)
			)
			(fill no)
			(layer "B.CrtYd")
		)
		(fp_rect
			(start 0.508 0.9398)
			(end -0.508 -0.9398)
			(stroke
				(width 0)
				(type default)
			)
			(fill no)
			(layer "B.Fab")
		)
		(pad "1" smd custom
			(at 0 -0.4445 270)
			(size 0.1397 0.1397)
			(layers "B.Cu" "B.Mask" "B.Paste")
			(net "CBL_PRSNT_N_5")
			(options
				(clearance outline)
				(anchor circle)
			)
			(primitives
				(gr_poly
					(pts
						(arc
							(start -0.1778 0.2794)
							(mid -0.249642 0.249642)
							(end -0.2794 0.1778)
						)
						(arc
							(start -0.2794 -0.1778)
							(mid -0.249642 -0.249642)
							(end -0.1778 -0.2794)
						)
						(arc
							(start 0.1778 -0.2794)
							(mid 0.249642 -0.249642)
							(end 0.2794 -0.1778)
						)
						(arc
							(start 0.2794 0.1778)
							(mid 0.249642 0.249642)
							(end 0.1778 0.2794)
						)
					)
					(width 0)
					(fill yes)
				)
			)
		)
		(pad "2" smd custom
			(at 0 0.4445 270)
			(size 0.1397 0.1397)
			(layers "B.Cu" "B.Mask" "B.Paste")
			(net "P3V3_STBY")
			(options
				(clearance outline)
				(anchor circle)
			)
			(primitives
				(gr_poly
					(pts
						(arc
							(start -0.1778 0.2794)
							(mid -0.249642 0.249642)
							(end -0.2794 0.1778)
						)
						(arc
							(start -0.2794 -0.1778)
							(mid -0.249642 -0.249642)
							(end -0.1778 -0.2794)
						)
						(arc
							(start 0.1778 -0.2794)
							(mid 0.249642 -0.249642)
							(end 0.2794 -0.1778)
						)
						(arc
							(start 0.2794 0.1778)
							(mid 0.249642 0.249642)
							(end 0.1778 0.2794)
						)
					)
					(width 0)
					(fill yes)
				)
			)
		)
	)
	(footprint ""
		(layer "B.Cu")
		(at 226.925124 -190.601092)
		(property "Reference" "R4145"
			(at 0 0 0)
			(layer "B.SilkS")
			(hide yes)
			(effects
				(font
					(size 1.27 1.27)
				)
				(justify mirror)
			)
		)
		(property "Value" "4K7R2F-GP"
			(at -0.064008 -3.993896 0)
			(unlocked yes)
			(layer "B.Fab")
			(hide yes)
			(effects
				(font
					(size 1.016 1.016)
					(thickness 0.1524)
				)
				(justify mirror)
			)
		)
		(property "Device Type" "R402H16"
			(at -0.064008 -5.517896 0)
			(unlocked yes)
			(layer "B.Fab")
			(hide yes)
			(effects
				(font
					(size 1.016 1.016)
					(thickness 0.1524)
				)
				(justify mirror)
			)
		)
		(duplicate_pad_numbers_are_jumpers no)
		(fp_line
			(start -0.508 -0.9398)
			(end 0.508 -0.9398)
			(stroke
				(width 0.1524)
				(type default)
			)
			(layer "B.SilkS")
		)
		(fp_line
			(start 0.508 -0.9398)
			(end 0.508 0.9398)
			(stroke
				(width 0.1524)
				(type default)
			)
			(layer "B.SilkS")
		)
		(fp_rect
			(start 0.508 0.9398)
			(end -0.508 -0.9398)
			(stroke
				(width 0)
				(type default)
			)
			(fill no)
			(layer "B.CrtYd")
		)
		(fp_rect
			(start 0.508 0.9398)
			(end -0.508 -0.9398)
			(stroke
				(width 0)
				(type default)
			)
			(fill no)
			(layer "B.Fab")
		)
		(pad "1" smd custom
			(at 0 -0.4445 180)
			(size 0.1397 0.1397)
			(layers "B.Cu" "B.Mask" "B.Paste")
			(net "SSD_PERST#8")
			(options
				(clearance outline)
				(anchor circle)
			)
			(primitives
				(gr_poly
					(pts
						(arc
							(start -0.1778 0.2794)
							(mid -0.249642 0.249642)
							(end -0.2794 0.1778)
						)
						(arc
							(start -0.2794 -0.1778)
							(mid -0.249642 -0.249642)
							(end -0.1778 -0.2794)
						)
						(arc
							(start 0.1778 -0.2794)
							(mid 0.249642 -0.249642)
							(end 0.2794 -0.1778)
						)
						(arc
							(start 0.2794 0.1778)
							(mid 0.249642 0.249642)
							(end 0.1778 0.2794)
						)
					)
					(width 0)
					(fill yes)
				)
			)
		)
		(pad "2" smd custom
			(at 0 0.4445 180)
			(size 0.1397 0.1397)
			(layers "B.Cu" "B.Mask" "B.Paste")
			(net "P3V3_STBY")
			(options
				(clearance outline)
				(anchor circle)
			)
			(primitives
				(gr_poly
					(pts
						(arc
							(start -0.1778 0.2794)
							(mid -0.249642 0.249642)
							(end -0.2794 0.1778)
						)
						(arc
							(start -0.2794 -0.1778)
							(mid -0.249642 -0.249642)
							(end -0.1778 -0.2794)
						)
						(arc
							(start 0.1778 -0.2794)
							(mid 0.249642 -0.249642)
							(end 0.2794 -0.1778)
						)
						(arc
							(start 0.2794 0.1778)
							(mid 0.249642 0.249642)
							(end 0.1778 0.2794)
						)
					)
					(width 0)
					(fill yes)
				)
			)
		)
	)
)
